# BASEBOARD_FAB2 (Tioga Pass) — schematic netlist excerpt (pin names and nets, part order shuffled) for the footprints in the layout excerpt that follows; sources: Cadence DE-HDL packaged netlist, KiCad conversion of Wiwynn_Tioga_Pass_MB.brd

C9A3  CAP_A  0.1UF 16V 10% X7R  pkg 0402V  page 175 : A = P3V3_STBY ; B = GND
RF19  RES  1.0K 0.1% CHIP  pkg 0402  page 223 : A = VR_PVDDQ_GHJ_AIREF1 ; B = ISENSE_PVDDQ_GHJ_PH1_IMON
R7F15  RES  7.87K 1.0% CHIP  pkg 0402  page 231 : A = VR_PVPP_ABC_ISET ; B = AGND_PVPP_ABC

(kicad_pcb
	(version 20260206)
	(generator "pcbnew")
	(generator_version "10.0")
	(general
		(thickness 1.6)
		(legacy_teardrops no)
	)
	(paper "A4")
	(title_block
		(title "Wiwynn_Tioga_Pass_MB.brd")
		(comment 1 "Tioga Pass / footprints 1384-1386 of 4770")
	)
	(layers
		(0 "F.Cu" signal "TOP")
		(4 "In1.Cu" signal "L2GND")
		(6 "In2.Cu" signal "L3")
		(8 "In3.Cu" signal "L4GND")
		(10 "In4.Cu" signal "L5")
		(12 "In5.Cu" signal "L6GND")
		(14 "In6.Cu" signal "L7VCC")
		(16 "In7.Cu" signal "L8VCC")
		(18 "In8.Cu" signal "L9GND")
		(20 "In9.Cu" signal "L10")
		(22 "In10.Cu" signal "L11GND")
		(24 "In11.Cu" signal "L12")
		(26 "In12.Cu" signal "L13GND")
		(2 "B.Cu" signal "BOTTOM")
		(9 "F.Adhes" user "F.Adhesive")
		(11 "B.Adhes" user "B.Adhesive")
		(13 "F.Paste" user "Package Geometry/Pastemask Top")
		(15 "B.Paste" user "Package Geometry/Pastemask Bottom")
		(5 "F.SilkS" user "Ref Des/Silkscreen Top")
		(7 "B.SilkS" user "Ref Des/Silkscreen Bottom")
		(1 "F.Mask" user "Board Geometry/Soldermask Top")
		(3 "B.Mask" user "Board Geometry/Soldermask Bottom")
		(17 "Dwgs.User" user "User.Drawings")
		(19 "Cmts.User" user "User.Comments")
		(21 "Eco1.User" user "User.Eco1")
		(23 "Eco2.User" user "User.Eco2")
		(25 "Edge.Cuts" user "Board Geometry/Outline")
		(27 "Margin" user)
		(31 "F.CrtYd" user "Package Geometry/Place Bound Top")
		(29 "B.CrtYd" user "Package Geometry/Place Bound Bottom")
		(35 "F.Fab" user "Ref Des/Assembly Top")
		(33 "B.Fab" user "Ref Des/Assembly Bottom")
	)
	(footprint ""
		(layer "F.Cu")
		(at 6.388608 -2.16281 -90)
		(property "Reference" "RF19"
			(at -0.8382 -0.67818 270)
			(unlocked yes)
			(layer "F.SilkS")
			(effects
				(font
					(size 0.4064 0.254)
					(thickness 0.1524)
				)
				(justify left)
			)
		)
		(property "Value" ""
			(at 0 0 270)
			(layer "F.Fab")
			(effects
				(font
					(size 1.27 1.27)
				)
			)
		)
		(duplicate_pad_numbers_are_jumpers no)
		(fp_poly
			(pts
				(xy -0.2794 -0.1016) (xy 0.2794 -0.1016) (xy 0.2794 0.9906) (xy -0.2794 0.9906)
			)
			(stroke
				(width 0)
				(type default)
			)
			(fill no)
			(layer "F.CrtYd")
		)
		(fp_line
			(start -0.2794 0.9906)
			(end 0.2794 0.9906)
			(stroke
				(width 0.1)
				(type default)
			)
			(layer "F.Fab")
		)
		(fp_line
			(start 0.2794 0.9906)
			(end 0.2794 -0.1016)
			(stroke
				(width 0.1)
				(type default)
			)
			(layer "F.Fab")
		)
		(fp_line
			(start -0.2794 -0.1016)
			(end -0.2794 0.9906)
			(stroke
				(width 0.1)
				(type default)
			)
			(layer "F.Fab")
		)
		(fp_line
			(start 0.2794 -0.1016)
			(end -0.2794 -0.1016)
			(stroke
				(width 0.1)
				(type default)
			)
			(layer "F.Fab")
		)
		(pad "1" smd rect
			(at 0 0 270)
			(size 0.508 0.508)
			(layers "F.Cu" "F.Mask" "F.Paste")
			(net "VR_PVDDQ_GHJ_AIREF1")
		)
		(pad "2" smd rect
			(at 0 0.889 270)
			(size 0.508 0.508)
			(layers "F.Cu" "F.Mask" "F.Paste")
			(net "ISENSE_PVDDQ_GHJ_PH1_IMON")
		)
		(zone
			(layer "F.Cu")
			(hatch none 0.5)
			(connect_pads
				(clearance 0)
			)
			(min_thickness 0.25)
			(keepout
				(tracks not_allowed)
				(vias allowed)
				(pads allowed)
				(copperpour not_allowed)
				(footprints allowed)
			)
			(placement
				(enabled no)
				(sheetname "")
			)
			(fill
				(thermal_gap 0.5)
				(thermal_bridge_width 0.5)
				(island_removal_mode 0)
			)
			(polygon
				(pts
					(xy 5.753608 -2.41681) (xy 5.753608 -1.90881) (xy 6.134608 -1.90881) (xy 6.134608 -2.41681)
				)
			)
		)
		(zone
			(layer "F.Cu")
			(hatch none 0.5)
			(connect_pads
				(clearance 0)
			)
			(min_thickness 0.25)
			(keepout
				(tracks allowed)
				(vias not_allowed)
				(pads allowed)
				(copperpour not_allowed)
				(footprints allowed)
			)
			(placement
				(enabled no)
				(sheetname "")
			)
			(fill
				(thermal_gap 0.5)
				(thermal_bridge_width 0.5)
				(island_removal_mode 0)
			)
			(polygon
				(pts
					(xy 6.134608 -2.41681) (xy 6.134608 -1.90881) (xy 5.753608 -1.90881) (xy 5.753608 -2.41681)
				)
			)
		)
	)
	(footprint ""
		(layer "F.Cu")
		(at 345.6178 -23.4823)
		(property "Reference" "R7F15"
			(at 0 0 0)
			(layer "F.SilkS")
			(hide yes)
			(effects
				(font
					(size 1.27 1.27)
				)
			)
		)
		(property "Value" ""
			(at 0 0 0)
			(layer "F.Fab")
			(effects
				(font
					(size 1.27 1.27)
				)
			)
		)
		(duplicate_pad_numbers_are_jumpers no)
		(fp_rect
			(start -0.2794 0.9906)
			(end 0.2794 -0.1016)
			(stroke
				(width 0)
				(type default)
			)
			(fill no)
			(layer "F.CrtYd")
		)
		(fp_line
			(start -0.2794 -0.1016)
			(end -0.2794 0.9906)
			(stroke
				(width 0.1)
				(type default)
			)
			(layer "F.Fab")
		)
		(fp_line
			(start -0.2794 0.9906)
			(end 0.2794 0.9906)
			(stroke
				(width 0.1)
				(type default)
			)
			(layer "F.Fab")
		)
		(fp_line
			(start 0.2794 -0.1016)
			(end -0.2794 -0.1016)
			(stroke
				(width 0.1)
				(type default)
			)
			(layer "F.Fab")
		)
		(fp_line
			(start 0.2794 0.9906)
			(end 0.2794 -0.1016)
			(stroke
				(width 0.1)
				(type default)
			)
			(layer "F.Fab")
		)
		(pad "1" smd rect
			(at 0 0)
			(size 0.508 0.508)
			(layers "F.Cu" "F.Mask" "F.Paste")
			(net "VR_PVPP_ABC_ISET")
		)
		(pad "2" smd rect
			(at 0 0.889)
			(size 0.508 0.508)
			(layers "F.Cu" "F.Mask" "F.Paste")
			(net "AGND_PVPP_ABC")
		)
		(zone
			(layer "F.Cu")
			(hatch none 0.5)
			(connect_pads
				(clearance 0)
			)
			(min_thickness 0.25)
			(keepout
				(tracks allowed)
				(vias not_allowed)
				(pads allowed)
				(copperpour not_allowed)
				(footprints allowed)
			)
			(placement
				(enabled no)
				(sheetname "")
			)
			(fill
				(thermal_gap 0.5)
				(thermal_bridge_width 0.5)
				(island_removal_mode 0)
			)
			(polygon
				(pts
					(xy 345.3638 -22.8473) (xy 345.8718 -22.8473) (xy 345.8718 -23.2283) (xy 345.3638 -23.2283)
				)
			)
		)
		(zone
			(layer "F.Cu")
			(hatch none 0.5)
			(connect_pads
				(clearance 0)
			)
			(min_thickness 0.25)
			(keepout
				(tracks not_allowed)
				(vias allowed)
				(pads allowed)
				(copperpour not_allowed)
				(footprints allowed)
			)
			(placement
				(enabled no)
				(sheetname "")
			)
			(fill
				(thermal_gap 0.5)
				(thermal_bridge_width 0.5)
				(island_removal_mode 0)
			)
			(polygon
				(pts
					(xy 345.3638 -22.8473) (xy 345.8718 -22.8473) (xy 345.8718 -23.2283) (xy 345.3638 -23.2283)
				)
			)
		)
	)
	(footprint ""
		(layer "F.Cu")
		(at 476.6691 -141.6177 180)
		(property "Reference" "C9A3"
			(at 0 0 180)
			(layer "F.SilkS")
			(hide yes)
			(effects
				(font
					(size 1.27 1.27)
				)
			)
		)
		(property "Value" ""
			(at 0 0 180)
			(layer "F.Fab")
			(effects
				(font
					(size 1.27 1.27)
				)
			)
		)
		(duplicate_pad_numbers_are_jumpers no)
		(fp_poly
			(pts
				(xy 0.3048 -0.1016) (xy 0.3048 0.9906) (xy -0.3048 0.9906) (xy -0.3048 -0.1016)
			)
			(stroke
				(width 0)
				(type default)
			)
			(fill no)
			(layer "F.CrtYd")
		)
		(fp_line
			(start 0.3048 0.9906)
			(end 0.3048 -0.1016)
			(stroke
				(width 0.1)
				(type default)
			)
			(layer "F.Fab")
		)
		(fp_line
			(start 0.3048 -0.1016)
			(end -0.3048 -0.1016)
			(stroke
				(width 0.1)
				(type default)
			)
			(layer "F.Fab")
		)
		(fp_line
			(start -0.3048 0.9906)
			(end 0.3048 0.9906)
			(stroke
				(width 0.1)
				(type default)
			)
			(layer "F.Fab")
		)
		(fp_line
			(start -0.3048 -0.1016)
			(end -0.3048 0.9906)
			(stroke
				(width 0.1)
				(type default)
			)
			(layer "F.Fab")
		)
		(pad "1" smd rect
			(at 0 0 180)
			(size 0.508 0.508)
			(layers "F.Cu" "F.Mask" "F.Paste")
			(net "P3V3_STBY")
		)
		(pad "2" smd rect
			(at 0 0.889 180)
			(size 0.508 0.508)
			(layers "F.Cu" "F.Mask" "F.Paste")
			(net "GND")
		)
		(zone
			(layer "F.Cu")
			(hatch none 0.5)
			(connect_pads
				(clearance 0)
			)
			(min_thickness 0.25)
			(keepout
				(tracks not_allowed)
				(vias allowed)
				(pads allowed)
				(copperpour not_allowed)
				(footprints allowed)
			)
			(placement
				(enabled no)
				(sheetname "")
			)
			(fill
				(thermal_gap 0.5)
				(thermal_bridge_width 0.5)
				(island_removal_mode 0)
			)
			(polygon
				(pts
					(xy 476.9231 -142.2527) (xy 476.4151 -142.2527) (xy 476.4151 -141.8717) (xy 476.9231 -141.8717)
				)
			)
		)
		(zone
			(layer "F.Cu")
			(hatch none 0.5)
			(connect_pads
				(clearance 0)
			)
			(min_thickness 0.25)
			(keepout
				(tracks allowed)
				(vias not_allowed)
				(pads allowed)
				(copperpour not_allowed)
				(footprints allowed)
			)
			(placement
				(enabled no)
				(sheetname "")
			)
			(fill
				(thermal_gap 0.5)
				(thermal_bridge_width 0.5)
				(island_removal_mode 0)
			)
			(polygon
				(pts
					(xy 476.9231 -141.8717) (xy 476.4151 -141.8717) (xy 476.4151 -142.2527) (xy 476.9231 -142.2527)
				)
			)
		)
	)
)
